# BASEBOARD_FAB2 (Tioga Pass) — schematic netlist excerpt (pin names and nets, part order shuffled) for the footprints in the layout excerpt that follows; sources: Cadence DE-HDL packaged netlist, KiCad conversion of Wiwynn_Tioga_Pass_MB.brd

XRU1  SOCKET_P_MECH_A  PLASTIC  pkg RIGHT  page 21

(kicad_pcb
	(version 20260206)
	(generator "pcbnew")
	(generator_version "10.0")
	(general
		(thickness 1.6)
		(legacy_teardrops no)
	)
	(paper "A4")
	(title_block
		(title "Wiwynn_Tioga_Pass_MB.brd")
		(comment 1 "Tioga Pass / footprints 367-367 of 4770")
	)
	(layers
		(0 "F.Cu" signal "TOP")
		(4 "In1.Cu" signal "L2GND")
		(6 "In2.Cu" signal "L3")
		(8 "In3.Cu" signal "L4GND")
		(10 "In4.Cu" signal "L5")
		(12 "In5.Cu" signal "L6GND")
		(14 "In6.Cu" signal "L7VCC")
		(16 "In7.Cu" signal "L8VCC")
		(18 "In8.Cu" signal "L9GND")
		(20 "In9.Cu" signal "L10")
		(22 "In10.Cu" signal "L11GND")
		(24 "In11.Cu" signal "L12")
		(26 "In12.Cu" signal "L13GND")
		(2 "B.Cu" signal "BOTTOM")
		(9 "F.Adhes" user "F.Adhesive")
		(11 "B.Adhes" user "B.Adhesive")
		(13 "F.Paste" user "Package Geometry/Pastemask Top")
		(15 "B.Paste" user "Package Geometry/Pastemask Bottom")
		(5 "F.SilkS" user "Ref Des/Silkscreen Top")
		(7 "B.SilkS" user "Ref Des/Silkscreen Bottom")
		(1 "F.Mask" user "Board Geometry/Soldermask Top")
		(3 "B.Mask" user "Board Geometry/Soldermask Bottom")
		(17 "Dwgs.User" user "User.Drawings")
		(19 "Cmts.User" user "User.Comments")
		(21 "Eco1.User" user "User.Eco1")
		(23 "Eco2.User" user "User.Eco2")
		(25 "Edge.Cuts" user "Board Geometry/Outline")
		(27 "Margin" user)
		(31 "F.CrtYd" user "Package Geometry/Place Bound Top")
		(29 "B.CrtYd" user "Package Geometry/Place Bound Bottom")
		(35 "F.Fab" user "Ref Des/Assembly Top")
		(33 "B.Fab" user "Ref Des/Assembly Bottom")
	)
	(footprint ""
		(layer "F.Cu")
		(at 289.222434 -77.449934 180)
		(property "Reference" "XRU1"
			(at -17.990566 32.886396 0)
			(unlocked yes)
			(layer "F.SilkS")
			(effects
				(font
					(size 0.7874 0.5842)
					(thickness 0.1524)
				)
				(justify left)
			)
		)
		(property "Value" ""
			(at 0 0 180)
			(layer "F.Fab")
			(effects
				(font
					(size 1.27 1.27)
				)
			)
		)
		(duplicate_pad_numbers_are_jumpers no)
	)
)
